# S9S_MB_2U (Grand Teton) — schematic netlist excerpt (pin names and nets, part order shuffled) for the footprints in the layout excerpt that follows; sources: Cadence DE-HDL packaged netlist, KiCad conversion of 03242023_DA0F0TMBIJ0_F0T_Motherboard_J_brd_V01_OCP.brd

PD16  ZENER_AC  5.0SMDJ14A IC  pkg D2723_SMCXC  page 304 : A = GND ; C = P12V_PSU_FUSE

(kicad_pcb
	(version 20260206)
	(generator "pcbnew")
	(generator_version "10.0")
	(general
		(thickness 1.6)
		(legacy_teardrops no)
	)
	(paper "A4")
	(title_block
		(title "03242023_DA0F0TMBIJ0_F0T_Motherboard_J_brd_V01_OCP.brd")
		(comment 1 "Grand Teton / footprints 5614-5614 of 6105")
	)
	(layers
		(0 "F.Cu" signal "TOP")
		(4 "In1.Cu" signal "GND")
		(6 "In2.Cu" signal "IN1")
		(8 "In3.Cu" signal "GND1")
		(10 "In4.Cu" signal "IN2")
		(12 "In5.Cu" signal "GND2")
		(14 "In6.Cu" signal "IN3")
		(16 "In7.Cu" signal "GND3")
		(18 "In8.Cu" signal "VCC")
		(20 "In9.Cu" signal "VCC1")
		(22 "In10.Cu" signal "GND4")
		(24 "In11.Cu" signal "IN4")
		(26 "In12.Cu" signal "GND5")
		(28 "In13.Cu" signal "IN5")
		(30 "In14.Cu" signal "GND6")
		(32 "In15.Cu" signal "IN6")
		(34 "In16.Cu" signal "GND7")
		(2 "B.Cu" signal "BOTTOM")
		(9 "F.Adhes" user "F.Adhesive")
		(11 "B.Adhes" user "B.Adhesive")
		(13 "F.Paste" user "Package Geometry/Pastemask Top")
		(15 "B.Paste" user "Package Geometry/Pastemask Bottom")
		(5 "F.SilkS" user "Ref Des/Silkscreen Top")
		(7 "B.SilkS" user "Ref Des/Silkscreen Bottom")
		(1 "F.Mask" user "Board Geometry/Soldermask Top")
		(3 "B.Mask" user "Board Geometry/Soldermask Bottom")
		(17 "Dwgs.User" user "User.Drawings")
		(19 "Cmts.User" user "User.Comments")
		(21 "Eco1.User" user "User.Eco1")
		(23 "Eco2.User" user "User.Eco2")
		(25 "Edge.Cuts" user "Board Geometry/Outline")
		(27 "Margin" user)
		(31 "F.CrtYd" user "Package Geometry/Place Bound Top")
		(29 "B.CrtYd" user "Package Geometry/Place Bound Bottom")
		(35 "F.Fab" user "Ref Des/Assembly Top")
		(33 "B.Fab" user "Ref Des/Assembly Bottom")
	)
	(footprint ""
		(layer "B.Cu")
		(at 263.2583 -419.164008 90)
		(property "Reference" "PD16"
			(at 4.59994 4.264152 90)
			(unlocked yes)
			(layer "B.SilkS")
			(effects
				(font
					(size 0.7874 0.5842)
					(thickness 0.1524)
				)
				(justify left mirror)
			)
		)
		(property "Value" ""
			(at 0 0 90)
			(layer "B.Fab")
			(effects
				(font
					(size 1.27 1.27)
				)
				(justify mirror)
			)
		)
		(duplicate_pad_numbers_are_jumpers no)
		(fp_line
			(start 4.664456 -3.109976)
			(end -4.743704 -3.109976)
			(stroke
				(width 0.1524)
				(type default)
			)
			(layer "B.SilkS")
		)
		(fp_line
			(start -4.183126 -3.109976)
			(end -4.794504 -3.109976)
			(stroke
				(width 0.1524)
				(type default)
			)
			(layer "B.SilkS")
		)
		(fp_line
			(start -4.511802 -3.109976)
			(end -4.207002 -3.109976)
			(stroke
				(width 0.1524)
				(type default)
			)
			(layer "B.SilkS")
		)
		(fp_line
			(start -4.6101 -3.109976)
			(end -4.283202 -3.109976)
			(stroke
				(width 0.1524)
				(type default)
			)
			(layer "B.SilkS")
		)
		(fp_line
			(start -4.695444 -3.109976)
			(end -4.695444 3.109976)
			(stroke
				(width 0.1524)
				(type default)
			)
			(layer "B.SilkS")
		)
		(fp_line
			(start -4.70535 -3.109976)
			(end -4.70535 3.109976)
			(stroke
				(width 0.1524)
				(type default)
			)
			(layer "B.SilkS")
		)
		(fp_line
			(start -4.70535 -3.109976)
			(end -4.70535 3.109976)
			(stroke
				(width 0.1524)
				(type default)
			)
			(layer "B.SilkS")
		)
		(fp_line
			(start -4.70535 -3.109976)
			(end -4.70535 3.109976)
			(stroke
				(width 0.1524)
				(type default)
			)
			(layer "B.SilkS")
		)
		(fp_line
			(start -4.805426 -3.109976)
			(end -4.805426 3.109976)
			(stroke
				(width 0.1524)
				(type default)
			)
			(layer "B.SilkS")
		)
		(fp_line
			(start -4.932426 -3.109976)
			(end -4.932426 3.109976)
			(stroke
				(width 0.1524)
				(type default)
			)
			(layer "B.SilkS")
		)
		(fp_line
			(start -5.008626 -3.109976)
			(end -5.008626 3.109976)
			(stroke
				(width 0.1524)
				(type default)
			)
			(layer "B.SilkS")
		)
		(fp_line
			(start -5.110226 -3.109976)
			(end -5.110226 3.109976)
			(stroke
				(width 0.1524)
				(type default)
			)
			(layer "B.SilkS")
		)
		(fp_line
			(start -5.211826 -3.109976)
			(end -5.211826 3.109976)
			(stroke
				(width 0.1524)
				(type default)
			)
			(layer "B.SilkS")
		)
		(fp_line
			(start -5.262626 -3.109976)
			(end -5.262626 3.109976)
			(stroke
				(width 0.1524)
				(type default)
			)
			(layer "B.SilkS")
		)
		(fp_line
			(start -5.313426 -3.109976)
			(end -5.313426 3.109976)
			(stroke
				(width 0.1524)
				(type default)
			)
			(layer "B.SilkS")
		)
		(fp_line
			(start -5.4102 -3.109976)
			(end -4.783074 -3.109976)
			(stroke
				(width 0.1524)
				(type default)
			)
			(layer "B.SilkS")
		)
		(fp_line
			(start 0.508 -1.016)
			(end -0.762 0)
			(stroke
				(width 0.1524)
				(type default)
			)
			(layer "B.SilkS")
		)
		(fp_line
			(start 1.0668 0)
			(end 0.6096 0)
			(stroke
				(width 0.1524)
				(type default)
			)
			(layer "B.SilkS")
		)
		(fp_line
			(start -0.762 0)
			(end -1.2192 0)
			(stroke
				(width 0.1524)
				(type default)
			)
			(layer "B.SilkS")
		)
		(fp_line
			(start -0.762 0)
			(end 0.508 1.016)
			(stroke
				(width 0.1524)
				(type default)
			)
			(layer "B.SilkS")
		)
		(fp_line
			(start 0.508 1.016)
			(end 0.508 -1.016)
			(stroke
				(width 0.1524)
				(type default)
			)
			(layer "B.SilkS")
		)
		(fp_line
			(start -0.762 1.27)
			(end -0.762 -1.27)
			(stroke
				(width 0.1524)
				(type default)
			)
			(layer "B.SilkS")
		)
		(fp_line
			(start -4.715002 3.035554)
			(end -4.7117 2.984754)
			(stroke
				(width 0.1524)
				(type default)
			)
			(layer "B.SilkS")
		)
		(fp_line
			(start 4.664456 3.109976)
			(end 4.664456 -3.109976)
			(stroke
				(width 0.1524)
				(type default)
			)
			(layer "B.SilkS")
		)
		(fp_line
			(start -4.156202 3.109976)
			(end -4.183126 3.109976)
			(stroke
				(width 0.1524)
				(type default)
			)
			(layer "B.SilkS")
		)
		(fp_line
			(start -4.743704 3.109976)
			(end -4.6101 3.109976)
			(stroke
				(width 0.1524)
				(type default)
			)
			(layer "B.SilkS")
		)
		(fp_line
			(start -4.743704 3.109976)
			(end -5.4102 3.109976)
			(stroke
				(width 0.1524)
				(type default)
			)
			(layer "B.SilkS")
		)
		(fp_line
			(start -4.769104 3.109976)
			(end 4.664456 3.109976)
			(stroke
				(width 0.1524)
				(type default)
			)
			(layer "B.SilkS")
		)
		(fp_line
			(start -4.794504 3.109976)
			(end -3.554984 3.109976)
			(stroke
				(width 0.1524)
				(type default)
			)
			(layer "B.SilkS")
		)
		(fp_line
			(start -5.4102 3.109976)
			(end -5.4102 -3.109976)
			(stroke
				(width 0.1524)
				(type default)
			)
			(layer "B.SilkS")
		)
		(fp_line
			(start 4.065016 -3.109976)
			(end -4.065016 -3.109976)
			(stroke
				(width 0.1)
				(type default)
			)
			(layer "B.Fab")
		)
		(fp_line
			(start -4.065016 -3.109976)
			(end -4.065016 3.109976)
			(stroke
				(width 0.1)
				(type default)
			)
			(layer "B.Fab")
		)
		(fp_line
			(start 4.065016 3.109976)
			(end 4.065016 -3.109976)
			(stroke
				(width 0.1)
				(type default)
			)
			(layer "B.Fab")
		)
		(fp_line
			(start -4.065016 3.109976)
			(end 4.065016 3.109976)
			(stroke
				(width 0.1)
				(type default)
			)
			(layer "B.Fab")
		)
		(fp_text user "+"
			(at 4.5974 0.24765 270)
			(unlocked yes)
			(layer "B.SilkS")
			(effects
				(font
					(size 1.905 1.4224)
					(thickness 0.1524)
				)
				(justify left mirror)
			)
		)
		(fp_text user "-"
			(at -6.643624 0.40005 270)
			(unlocked yes)
			(layer "B.SilkS")
			(effects
				(font
					(size 1.905 1.4224)
					(thickness 0.1524)
				)
				(justify left mirror)
			)
		)
		(fp_text user "+"
			(at 4.5974 0.24765 270)
			(unlocked yes)
			(layer "B.Fab")
			(effects
				(font
					(size 1.905 1.4224)
					(thickness 0.1524)
				)
				(justify left mirror)
			)
		)
		(fp_text user "-"
			(at -6.643624 0.40005 270)
			(unlocked yes)
			(layer "B.Fab")
			(effects
				(font
					(size 1.905 1.4224)
					(thickness 0.1524)
				)
				(justify left mirror)
			)
		)
		(pad "A" smd rect
			(at 3.299968 0 90)
			(size 2.413 3.302)
			(layers "B.Cu" "B.Mask" "B.Paste")
			(net "GND")
		)
		(pad "C" smd rect
			(at -3.299968 0 90)
			(size 2.413 3.302)
			(layers "B.Cu" "B.Mask" "B.Paste")
			(net "P12V_PSU_FUSE")
		)
	)
)
